# S9S_MB_2U (Grand Teton) — schematic netlist excerpt (pin names and nets, part order shuffled) for the footprints in the layout excerpt that follows; sources: Cadence DE-HDL packaged netlist, KiCad conversion of 03242023_DA0F0TMBIJ0_F0T_Motherboard_J_brd_V01_OCP.brd

PR1784  Q_RES  3.3 1% CHIP  pkg 0402LF  page 279 : A = SW_PVCCD_HV_CPU0_BOOT1 ; B = SW_PVCCD_HV_CPU0_BOOT1_R
PR139  Q_RES  8.87K 1% EMPTY  pkg 0402LF  page 269 : A = PVCCIN_CPU0_LSET5 ; B = GND

(kicad_pcb
	(version 20260206)
	(generator "pcbnew")
	(generator_version "10.0")
	(general
		(thickness 1.6)
		(legacy_teardrops no)
	)
	(paper "A4")
	(title_block
		(title "03242023_DA0F0TMBIJ0_F0T_Motherboard_J_brd_V01_OCP.brd")
		(comment 1 "Grand Teton / footprints 1016-1017 of 6105")
	)
	(layers
		(0 "F.Cu" signal "TOP")
		(4 "In1.Cu" signal "GND")
		(6 "In2.Cu" signal "IN1")
		(8 "In3.Cu" signal "GND1")
		(10 "In4.Cu" signal "IN2")
		(12 "In5.Cu" signal "GND2")
		(14 "In6.Cu" signal "IN3")
		(16 "In7.Cu" signal "GND3")
		(18 "In8.Cu" signal "VCC")
		(20 "In9.Cu" signal "VCC1")
		(22 "In10.Cu" signal "GND4")
		(24 "In11.Cu" signal "IN4")
		(26 "In12.Cu" signal "GND5")
		(28 "In13.Cu" signal "IN5")
		(30 "In14.Cu" signal "GND6")
		(32 "In15.Cu" signal "IN6")
		(34 "In16.Cu" signal "GND7")
		(2 "B.Cu" signal "BOTTOM")
		(9 "F.Adhes" user "F.Adhesive")
		(11 "B.Adhes" user "B.Adhesive")
		(13 "F.Paste" user "Package Geometry/Pastemask Top")
		(15 "B.Paste" user "Package Geometry/Pastemask Bottom")
		(5 "F.SilkS" user "Ref Des/Silkscreen Top")
		(7 "B.SilkS" user "Ref Des/Silkscreen Bottom")
		(1 "F.Mask" user "Board Geometry/Soldermask Top")
		(3 "B.Mask" user "Board Geometry/Soldermask Bottom")
		(17 "Dwgs.User" user "User.Drawings")
		(19 "Cmts.User" user "User.Comments")
		(21 "Eco1.User" user "User.Eco1")
		(23 "Eco2.User" user "User.Eco2")
		(25 "Edge.Cuts" user "Board Geometry/Outline")
		(27 "Margin" user)
		(31 "F.CrtYd" user "Package Geometry/Place Bound Top")
		(29 "B.CrtYd" user "Package Geometry/Place Bound Bottom")
		(35 "F.Fab" user "Ref Des/Assembly Top")
		(33 "B.Fab" user "Ref Des/Assembly Bottom")
	)
	(footprint ""
		(layer "F.Cu")
		(at 420.473632 -161.490914)
		(property "Reference" "PR1784"
			(at 0 0 0)
			(layer "F.SilkS")
			(hide yes)
			(effects
				(font
					(size 1.27 1.27)
				)
			)
		)
		(property "Value" ""
			(at 0 0 0)
			(layer "F.Fab")
			(effects
				(font
					(size 1.27 1.27)
				)
			)
		)
		(duplicate_pad_numbers_are_jumpers no)
		(fp_line
			(start -0.7874 -0.4064)
			(end 0.7874 -0.4064)
			(stroke
				(width 0.1524)
				(type default)
			)
			(layer "F.SilkS")
		)
		(fp_line
			(start -0.7874 0.4064)
			(end -0.7874 -0.4064)
			(stroke
				(width 0.1524)
				(type default)
			)
			(layer "F.SilkS")
		)
		(fp_line
			(start 0.7874 -0.4064)
			(end 0.7874 0.4064)
			(stroke
				(width 0.1524)
				(type default)
			)
			(layer "F.SilkS")
		)
		(fp_line
			(start 0.7874 0.4064)
			(end -0.7874 0.4064)
			(stroke
				(width 0.1524)
				(type default)
			)
			(layer "F.SilkS")
		)
		(fp_line
			(start -0.67945 -0.305054)
			(end -0.12065 -0.305054)
			(stroke
				(width 0.1)
				(type default)
			)
			(layer "F.Fab")
		)
		(fp_line
			(start -0.67945 0.3048)
			(end -0.67945 -0.305054)
			(stroke
				(width 0.1)
				(type default)
			)
			(layer "F.Fab")
		)
		(fp_line
			(start -0.12065 -0.305054)
			(end -0.12065 -0.2794)
			(stroke
				(width 0.1)
				(type default)
			)
			(layer "F.Fab")
		)
		(fp_line
			(start -0.12065 -0.2794)
			(end 0.12065 -0.2794)
			(stroke
				(width 0.1)
				(type default)
			)
			(layer "F.Fab")
		)
		(fp_line
			(start -0.12065 0.2794)
			(end -0.12065 0.3048)
			(stroke
				(width 0.1)
				(type default)
			)
			(layer "F.Fab")
		)
		(fp_line
			(start -0.12065 0.3048)
			(end -0.67945 0.3048)
			(stroke
				(width 0.1)
				(type default)
			)
			(layer "F.Fab")
		)
		(fp_line
			(start 0.120396 0.2794)
			(end -0.12065 0.2794)
			(stroke
				(width 0.1)
				(type default)
			)
			(layer "F.Fab")
		)
		(fp_line
			(start 0.120396 0.3048)
			(end 0.120396 0.2794)
			(stroke
				(width 0.1)
				(type default)
			)
			(layer "F.Fab")
		)
		(fp_line
			(start 0.12065 -0.3048)
			(end 0.67945 -0.3048)
			(stroke
				(width 0.1)
				(type default)
			)
			(layer "F.Fab")
		)
		(fp_line
			(start 0.12065 -0.2794)
			(end 0.12065 -0.3048)
			(stroke
				(width 0.1)
				(type default)
			)
			(layer "F.Fab")
		)
		(fp_line
			(start 0.67945 -0.3048)
			(end 0.67945 0.3048)
			(stroke
				(width 0.1)
				(type default)
			)
			(layer "F.Fab")
		)
		(fp_line
			(start 0.67945 0.3048)
			(end 0.120396 0.3048)
			(stroke
				(width 0.1)
				(type default)
			)
			(layer "F.Fab")
		)
		(pad "1" smd circle
			(at -0.40005 0)
			(size 0 0)
			(layers "F.Cu" "F.Mask" "F.Paste")
			(net "SW_PVCCD_HV_CPU0_BOOT1")
		)
		(pad "2" smd circle
			(at 0.40005 0)
			(size 0 0)
			(layers "F.Cu" "F.Mask" "F.Paste")
			(net "SW_PVCCD_HV_CPU0_BOOT1_R")
		)
	)
	(footprint ""
		(layer "F.Cu")
		(at 376.2883 -342.270334)
		(property "Reference" "PR139"
			(at 0 0 0)
			(layer "F.SilkS")
			(hide yes)
			(effects
				(font
					(size 1.27 1.27)
				)
			)
		)
		(property "Value" ""
			(at 0 0 0)
			(layer "F.Fab")
			(effects
				(font
					(size 1.27 1.27)
				)
			)
		)
		(duplicate_pad_numbers_are_jumpers no)
		(fp_line
			(start -0.7874 -0.4064)
			(end 0.7874 -0.4064)
			(stroke
				(width 0.1524)
				(type default)
			)
			(layer "F.SilkS")
		)
		(fp_line
			(start -0.7874 0.4064)
			(end -0.7874 -0.4064)
			(stroke
				(width 0.1524)
				(type default)
			)
			(layer "F.SilkS")
		)
		(fp_line
			(start 0.7874 -0.4064)
			(end 0.7874 0.4064)
			(stroke
				(width 0.1524)
				(type default)
			)
			(layer "F.SilkS")
		)
		(fp_line
			(start 0.7874 0.4064)
			(end -0.7874 0.4064)
			(stroke
				(width 0.1524)
				(type default)
			)
			(layer "F.SilkS")
		)
		(fp_line
			(start -0.67945 -0.305054)
			(end -0.12065 -0.305054)
			(stroke
				(width 0.1)
				(type default)
			)
			(layer "F.Fab")
		)
		(fp_line
			(start -0.67945 0.3048)
			(end -0.67945 -0.305054)
			(stroke
				(width 0.1)
				(type default)
			)
			(layer "F.Fab")
		)
		(fp_line
			(start -0.12065 -0.305054)
			(end -0.12065 -0.2794)
			(stroke
				(width 0.1)
				(type default)
			)
			(layer "F.Fab")
		)
		(fp_line
			(start -0.12065 -0.2794)
			(end 0.12065 -0.2794)
			(stroke
				(width 0.1)
				(type default)
			)
			(layer "F.Fab")
		)
		(fp_line
			(start -0.12065 0.2794)
			(end -0.12065 0.3048)
			(stroke
				(width 0.1)
				(type default)
			)
			(layer "F.Fab")
		)
		(fp_line
			(start -0.12065 0.3048)
			(end -0.67945 0.3048)
			(stroke
				(width 0.1)
				(type default)
			)
			(layer "F.Fab")
		)
		(fp_line
			(start 0.120396 0.2794)
			(end -0.12065 0.2794)
			(stroke
				(width 0.1)
				(type default)
			)
			(layer "F.Fab")
		)
		(fp_line
			(start 0.120396 0.3048)
			(end 0.120396 0.2794)
			(stroke
				(width 0.1)
				(type default)
			)
			(layer "F.Fab")
		)
		(fp_line
			(start 0.12065 -0.3048)
			(end 0.67945 -0.3048)
			(stroke
				(width 0.1)
				(type default)
			)
			(layer "F.Fab")
		)
		(fp_line
			(start 0.12065 -0.2794)
			(end 0.12065 -0.3048)
			(stroke
				(width 0.1)
				(type default)
			)
			(layer "F.Fab")
		)
		(fp_line
			(start 0.67945 -0.3048)
			(end 0.67945 0.3048)
			(stroke
				(width 0.1)
				(type default)
			)
			(layer "F.Fab")
		)
		(fp_line
			(start 0.67945 0.3048)
			(end 0.120396 0.3048)
			(stroke
				(width 0.1)
				(type default)
			)
			(layer "F.Fab")
		)
		(pad "1" smd circle
			(at -0.40005 0)
			(size 0 0)
			(layers "F.Cu" "F.Mask" "F.Paste")
			(net "PVCCIN_CPU0_LSET5")
		)
		(pad "2" smd circle
			(at 0.40005 0)
			(size 0 0)
			(layers "F.Cu" "F.Mask" "F.Paste")
			(net "GND")
		)
	)
)
